# S9S_MB_2U (Grand Teton) — schematic netlist excerpt (pin names and nets, part order shuffled) for the footprints in the layout excerpt that follows; sources: Cadence DE-HDL packaged netlist, KiCad conversion of 03242023_DA0F0TMBIJ0_F0T_Motherboard_J_brd_V01_OCP.brd

C1245  Q_CAP  47UF 6.3V 20% X6S  pkg C0805  page 189 : A = P3V3_AUX ; B = GND
R4300  Q_RES  100 1% CHIP  pkg 0402LF  page 125 : A = PWRGD_DRAMPWRGD_CPU1_CD_LVC1_R2 ; B = PWRGD_DRAMPWRGD_CPU1_CD_LVC1_R
PR134  Q_RES  2.2 1% CHIP  pkg 0402LF  page 270 : A = PVCCIN_CPU0_PVCC ; B = PVCCIN_CPU0_VDD8

(kicad_pcb
	(version 20260206)
	(generator "pcbnew")
	(generator_version "10.0")
	(general
		(thickness 1.6)
		(legacy_teardrops no)
	)
	(paper "A4")
	(title_block
		(title "03242023_DA0F0TMBIJ0_F0T_Motherboard_J_brd_V01_OCP.brd")
		(comment 1 "Grand Teton / footprints 5866-5868 of 6105")
	)
	(layers
		(0 "F.Cu" signal "TOP")
		(4 "In1.Cu" signal "GND")
		(6 "In2.Cu" signal "IN1")
		(8 "In3.Cu" signal "GND1")
		(10 "In4.Cu" signal "IN2")
		(12 "In5.Cu" signal "GND2")
		(14 "In6.Cu" signal "IN3")
		(16 "In7.Cu" signal "GND3")
		(18 "In8.Cu" signal "VCC")
		(20 "In9.Cu" signal "VCC1")
		(22 "In10.Cu" signal "GND4")
		(24 "In11.Cu" signal "IN4")
		(26 "In12.Cu" signal "GND5")
		(28 "In13.Cu" signal "IN5")
		(30 "In14.Cu" signal "GND6")
		(32 "In15.Cu" signal "IN6")
		(34 "In16.Cu" signal "GND7")
		(2 "B.Cu" signal "BOTTOM")
		(9 "F.Adhes" user "F.Adhesive")
		(11 "B.Adhes" user "B.Adhesive")
		(13 "F.Paste" user "Package Geometry/Pastemask Top")
		(15 "B.Paste" user "Package Geometry/Pastemask Bottom")
		(5 "F.SilkS" user "Ref Des/Silkscreen Top")
		(7 "B.SilkS" user "Ref Des/Silkscreen Bottom")
		(1 "F.Mask" user "Board Geometry/Soldermask Top")
		(3 "B.Mask" user "Board Geometry/Soldermask Bottom")
		(17 "Dwgs.User" user "User.Drawings")
		(19 "Cmts.User" user "User.Comments")
		(21 "Eco1.User" user "User.Eco1")
		(23 "Eco2.User" user "User.Eco2")
		(25 "Edge.Cuts" user "Board Geometry/Outline")
		(27 "Margin" user)
		(31 "F.CrtYd" user "Package Geometry/Place Bound Top")
		(29 "B.CrtYd" user "Package Geometry/Place Bound Bottom")
		(35 "F.Fab" user "Ref Des/Assembly Top")
		(33 "B.Fab" user "Ref Des/Assembly Bottom")
	)
	(footprint ""
		(layer "B.Cu")
		(at 65.364868 -195.632578 -90)
		(property "Reference" "R4300"
			(at 0 0 90)
			(layer "B.SilkS")
			(hide yes)
			(effects
				(font
					(size 1.27 1.27)
				)
				(justify mirror)
			)
		)
		(property "Value" ""
			(at 0 0 90)
			(layer "B.Fab")
			(effects
				(font
					(size 1.27 1.27)
				)
				(justify mirror)
			)
		)
		(duplicate_pad_numbers_are_jumpers no)
		(fp_line
			(start -0.7874 0.4064)
			(end 0.7874 0.4064)
			(stroke
				(width 0.1524)
				(type default)
			)
			(layer "B.SilkS")
		)
		(fp_line
			(start 0.7874 0.4064)
			(end 0.7874 -0.4064)
			(stroke
				(width 0.1524)
				(type default)
			)
			(layer "B.SilkS")
		)
		(fp_line
			(start -0.7874 -0.4064)
			(end -0.7874 0.4064)
			(stroke
				(width 0.1524)
				(type default)
			)
			(layer "B.SilkS")
		)
		(fp_line
			(start 0.7874 -0.4064)
			(end -0.7874 -0.4064)
			(stroke
				(width 0.1524)
				(type default)
			)
			(layer "B.SilkS")
		)
		(fp_line
			(start -0.67945 0.3048)
			(end -0.120396 0.3048)
			(stroke
				(width 0.1)
				(type default)
			)
			(layer "B.Fab")
		)
		(fp_line
			(start -0.120396 0.3048)
			(end -0.120396 0.2794)
			(stroke
				(width 0.1)
				(type default)
			)
			(layer "B.Fab")
		)
		(fp_line
			(start 0.12065 0.3048)
			(end 0.67945 0.3048)
			(stroke
				(width 0.1)
				(type default)
			)
			(layer "B.Fab")
		)
		(fp_line
			(start 0.67945 0.3048)
			(end 0.67945 -0.305054)
			(stroke
				(width 0.1)
				(type default)
			)
			(layer "B.Fab")
		)
		(fp_line
			(start -0.120396 0.2794)
			(end 0.12065 0.2794)
			(stroke
				(width 0.1)
				(type default)
			)
			(layer "B.Fab")
		)
		(fp_line
			(start 0.12065 0.2794)
			(end 0.12065 0.3048)
			(stroke
				(width 0.1)
				(type default)
			)
			(layer "B.Fab")
		)
		(fp_line
			(start -0.12065 -0.2794)
			(end -0.12065 -0.3048)
			(stroke
				(width 0.1)
				(type default)
			)
			(layer "B.Fab")
		)
		(fp_line
			(start 0.12065 -0.2794)
			(end -0.12065 -0.2794)
			(stroke
				(width 0.1)
				(type default)
			)
			(layer "B.Fab")
		)
		(fp_line
			(start -0.67945 -0.3048)
			(end -0.67945 0.3048)
			(stroke
				(width 0.1)
				(type default)
			)
			(layer "B.Fab")
		)
		(fp_line
			(start -0.12065 -0.3048)
			(end -0.67945 -0.3048)
			(stroke
				(width 0.1)
				(type default)
			)
			(layer "B.Fab")
		)
		(fp_line
			(start 0.12065 -0.305054)
			(end 0.12065 -0.2794)
			(stroke
				(width 0.1)
				(type default)
			)
			(layer "B.Fab")
		)
		(fp_line
			(start 0.67945 -0.305054)
			(end 0.12065 -0.305054)
			(stroke
				(width 0.1)
				(type default)
			)
			(layer "B.Fab")
		)
		(pad "1" smd circle
			(at 0.40005 0 90)
			(size 0 0)
			(layers "B.Cu" "B.Mask" "B.Paste")
			(net "PWRGD_DRAMPWRGD_CPU1_CD_LVC1_R2")
		)
		(pad "2" smd circle
			(at -0.40005 0 90)
			(size 0 0)
			(layers "B.Cu" "B.Mask" "B.Paste")
			(net "PWRGD_DRAMPWRGD_CPU1_CD_LVC1_R")
		)
	)
	(footprint ""
		(layer "B.Cu")
		(at 383.429256 -343.927938 -90)
		(property "Reference" "PR134"
			(at 0 0 90)
			(layer "B.SilkS")
			(hide yes)
			(effects
				(font
					(size 1.27 1.27)
				)
				(justify mirror)
			)
		)
		(property "Value" ""
			(at 0 0 90)
			(layer "B.Fab")
			(effects
				(font
					(size 1.27 1.27)
				)
				(justify mirror)
			)
		)
		(duplicate_pad_numbers_are_jumpers no)
		(fp_line
			(start -0.7874 0.4064)
			(end 0.7874 0.4064)
			(stroke
				(width 0.1524)
				(type default)
			)
			(layer "B.SilkS")
		)
		(fp_line
			(start 0.7874 0.4064)
			(end 0.7874 -0.4064)
			(stroke
				(width 0.1524)
				(type default)
			)
			(layer "B.SilkS")
		)
		(fp_line
			(start -0.7874 -0.4064)
			(end -0.7874 0.4064)
			(stroke
				(width 0.1524)
				(type default)
			)
			(layer "B.SilkS")
		)
		(fp_line
			(start 0.7874 -0.4064)
			(end -0.7874 -0.4064)
			(stroke
				(width 0.1524)
				(type default)
			)
			(layer "B.SilkS")
		)
		(fp_line
			(start -0.67945 0.3048)
			(end -0.120396 0.3048)
			(stroke
				(width 0.1)
				(type default)
			)
			(layer "B.Fab")
		)
		(fp_line
			(start -0.120396 0.3048)
			(end -0.120396 0.2794)
			(stroke
				(width 0.1)
				(type default)
			)
			(layer "B.Fab")
		)
		(fp_line
			(start 0.12065 0.3048)
			(end 0.67945 0.3048)
			(stroke
				(width 0.1)
				(type default)
			)
			(layer "B.Fab")
		)
		(fp_line
			(start 0.67945 0.3048)
			(end 0.67945 -0.305054)
			(stroke
				(width 0.1)
				(type default)
			)
			(layer "B.Fab")
		)
		(fp_line
			(start -0.120396 0.2794)
			(end 0.12065 0.2794)
			(stroke
				(width 0.1)
				(type default)
			)
			(layer "B.Fab")
		)
		(fp_line
			(start 0.12065 0.2794)
			(end 0.12065 0.3048)
			(stroke
				(width 0.1)
				(type default)
			)
			(layer "B.Fab")
		)
		(fp_line
			(start -0.12065 -0.2794)
			(end -0.12065 -0.3048)
			(stroke
				(width 0.1)
				(type default)
			)
			(layer "B.Fab")
		)
		(fp_line
			(start 0.12065 -0.2794)
			(end -0.12065 -0.2794)
			(stroke
				(width 0.1)
				(type default)
			)
			(layer "B.Fab")
		)
		(fp_line
			(start -0.67945 -0.3048)
			(end -0.67945 0.3048)
			(stroke
				(width 0.1)
				(type default)
			)
			(layer "B.Fab")
		)
		(fp_line
			(start -0.12065 -0.3048)
			(end -0.67945 -0.3048)
			(stroke
				(width 0.1)
				(type default)
			)
			(layer "B.Fab")
		)
		(fp_line
			(start 0.12065 -0.305054)
			(end 0.12065 -0.2794)
			(stroke
				(width 0.1)
				(type default)
			)
			(layer "B.Fab")
		)
		(fp_line
			(start 0.67945 -0.305054)
			(end 0.12065 -0.305054)
			(stroke
				(width 0.1)
				(type default)
			)
			(layer "B.Fab")
		)
		(pad "1" smd circle
			(at 0.40005 0 90)
			(size 0 0)
			(layers "B.Cu" "B.Mask" "B.Paste")
			(net "PVCCIN_CPU0_PVCC")
		)
		(pad "2" smd circle
			(at -0.40005 0 90)
			(size 0 0)
			(layers "B.Cu" "B.Mask" "B.Paste")
			(net "PVCCIN_CPU0_VDD8")
		)
	)
	(footprint ""
		(layer "B.Cu")
		(at 322.682616 -66.937128 -90)
		(property "Reference" "C1245"
			(at 0 0 90)
			(layer "B.SilkS")
			(hide yes)
			(effects
				(font
					(size 1.27 1.27)
				)
				(justify mirror)
			)
		)
		(property "Value" ""
			(at 0 0 90)
			(layer "B.Fab")
			(effects
				(font
					(size 1.27 1.27)
				)
				(justify mirror)
			)
		)
		(duplicate_pad_numbers_are_jumpers no)
		(fp_line
			(start -1.524 0.762)
			(end 1.524 0.762)
			(stroke
				(width 0.1524)
				(type default)
			)
			(layer "B.SilkS")
		)
		(fp_line
			(start 1.524 0.762)
			(end 1.524 -0.762)
			(stroke
				(width 0.1524)
				(type default)
			)
			(layer "B.SilkS")
		)
		(fp_line
			(start -1.524 -0.762)
			(end -1.524 0.762)
			(stroke
				(width 0.1524)
				(type default)
			)
			(layer "B.SilkS")
		)
		(fp_line
			(start 1.524 -0.762)
			(end -1.524 -0.762)
			(stroke
				(width 0.1524)
				(type default)
			)
			(layer "B.SilkS")
		)
		(fp_line
			(start -1.1049 0.724916)
			(end -1.1049 -0.724916)
			(stroke
				(width 0.1)
				(type default)
			)
			(layer "B.Fab")
		)
		(fp_line
			(start 1.1049 0.724916)
			(end -1.1049 0.724916)
			(stroke
				(width 0.1)
				(type default)
			)
			(layer "B.Fab")
		)
		(fp_line
			(start -1.1049 -0.724916)
			(end 1.1049 -0.724916)
			(stroke
				(width 0.1)
				(type default)
			)
			(layer "B.Fab")
		)
		(fp_line
			(start 1.1049 -0.724916)
			(end 1.1049 0.724916)
			(stroke
				(width 0.1)
				(type default)
			)
			(layer "B.Fab")
		)
		(pad "1" smd rect
			(at 0.889 0 270)
			(size 1.016 1.27)
			(layers "B.Cu" "B.Mask" "B.Paste")
			(net "P3V3_AUX")
		)
		(pad "2" smd rect
			(at -0.889 0 270)
			(size 1.016 1.27)
			(layers "B.Cu" "B.Mask" "B.Paste")
			(net "GND")
		)
	)
)
